# BASEBOARD_FAB2 (Tioga Pass) — schematic parts with pin connectivity, parts 4665–4665 of 4751; source: Cadence DE-HDL packaged netlist (pstxprt.dat, pstxnet.dat, pstchip.dat)

U5D1  SKX_EXT_B  IC  pkg BGA1  page 21  (pins 3052-3390 of 3647)
  F81  DDR1_DQ(20)  BI  = M_B_DQ<20>
  F83  RSVD(276)  BI  = TP_CPU0_RSVD_276
  G2  RSVD(275)  BI  = TP_CPU0_RSVD_275
  G4  VSS(1136)  GROUND  = GND
  G6  UPI1_TX_DN(4)  OUT  = UPI_CPU0_CPU1_P1P1_DN<15>
  G8  VSS(1135)  GROUND  = GND
  G10  UPI1_TX_DN(9)  OUT  = UPI_CPU0_CPU1_P1P1_DN<10>
  G12  UPI1_TX_DP(10)  OUT  = UPI_CPU0_CPU1_P1P1_DP<9>
  G14  UPI1_TX_DN(11)  OUT  = UPI_CPU0_CPU1_P1P1_DN<8>
  G16  UPI1_TX_DP(14)  OUT  = UPI_CPU0_CPU1_P1P1_DP<5>
  G18  UPI1_TX_DN(16)  OUT  = UPI_CPU0_CPU1_P1P1_DN<3>
  G20  UPI1_TX_DP(18)  OUT  = UPI_CPU0_CPU1_P1P1_DP<1>
  G22  VSS(1134)  GROUND  = GND
  G24  VSS(1133)  GROUND  = GND
  G26  VSS(1132)  GROUND  = GND
  G28  DDR1_DQS_DN(6)  BI  = M_B_DQS_DN<6>
  G30  VSS(1131)  GROUND  = GND
  G32  VSS(1130)  GROUND  = GND
  G34  DDR1_DQS_DN(5)  BI  = M_B_DQS_DN<5>
  G36  VSS(1129)  GROUND  = GND
  G38  VSS(1128)  GROUND  = GND
  G40  DDR0_DQS_DN(4)  BI  = M_A_DQS_DN<4>
  G42  VSS(1127)  GROUND  = GND
  G46  DDR0_CID(2)  OUT  = M_A_C<2>
  G48  DDR0_ODT(3)  OUT  = M_A_ODT<3>
  G50  DDR0_ODT(2)  OUT  = M_A_ODT<2>
  G52  DDR0_CS_N(0)  OUT  = M_A_CS_N<0>
  G54  DDR0_BA(1)  OUT  = M_A_BA<1>
  G56  DDR0_CLK_DP(2)  OUT  = M_A_CLK_DP<2>
  G58  DDR0_MA(4)  OUT  = M_A_MA<4>
  G60  DDR0_MA(7)  OUT  = M_A_MA<7>
  G62  DDR0_MA(11)  OUT  = M_A_MA<11>
  G64  RSVD(274)  BI  = TP_CPU0_RSVD_274
  G66  VSS(1126)  GROUND  = GND
  G68  DDR1_DQS_DN(17)  BI  = M_B_DQS_DN<17>
  G70  VSS(1125)  GROUND  = GND
  G72  DDR1_DQ(31)  BI  = M_B_DQ<31>
  G74  DDR1_DQ(29)  BI  = M_B_DQ<29>
  G76  VSS(1124)  GROUND  = GND
  G78  VSS(1123)  GROUND  = GND
  G80  VSS(1122)  GROUND  = GND
  G82  VSS(1121)  GROUND  = GND
  G84  RSVD(273)  BI  = TP_CPU0_RSVD_273
  H1  RSVD(272)  BI  = TP_CPU0_RSVD_272
  H3  VSS(1120)  GROUND  = GND
  H5  UPI1_TX_DP(3)  OUT  = UPI_CPU0_CPU1_P1P1_DP<16>
  H7  UPI1_TX_DN(5)  OUT  = UPI_CPU0_CPU1_P1P1_DN<14>
  H9  UPI1_TX_DP(9)  OUT  = UPI_CPU0_CPU1_P1P1_DP<10>
  H11  VSS(1119)  GROUND  = GND
  H13  VCCIO(59)  POWER  = PVCCIO_CPU0
  H15  UPI1_TX_DP(13)  OUT  = UPI_CPU0_CPU1_P1P1_DP<6>
  H17  UPI1_TX_DN(14)  OUT  = UPI_CPU0_CPU1_P1P1_DN<5>
  H19  UPI1_TX_DP(17)  OUT  = UPI_CPU0_CPU1_P1P1_DP<2>
  H21  UPI1_TX_DN(19)  OUT  = UPI_CPU0_CPU1_P1P1_DN<0>
  H23  DDR0_DQ(62)  BI  = M_A_DQ<62>
  H25  VSS(1118)  GROUND  = GND
  H27  VSS(1117)  GROUND  = GND
  H29  VSS(1116)  GROUND  = GND
  H31  VSS(1115)  GROUND  = GND
  H33  VSS(1114)  GROUND  = GND
  H35  VSS(1113)  GROUND  = GND
  H37  VSS(1112)  GROUND  = GND
  H39  VSS(1111)  GROUND  = GND
  H41  VSS(1110)  GROUND  = GND
  H43  DDR1_DQ(33)  BI  = M_B_DQ<33>
  H45  VSS(153)  GROUND  = GND
  H47  VSS(190)  GROUND  = GND
  H49  VSS(219)  GROUND  = GND
  H51  VSS(233)  GROUND  = GND
  H53  VSS(304)  GROUND  = GND
  H55  VSS(352)  GROUND  = GND
  H57  VSS(379)  GROUND  = GND
  H59  VSS(399)  GROUND  = GND
  H61  VSS(407)  GROUND  = GND
  H63  VSS(428)  GROUND  = GND
  H65  VSS(1109)  GROUND  = GND
  H67  DDR1_ECC(6)  BI  = M_B_ECC<6>
  H69  DDR1_ECC(1)  BI  = M_B_ECC<1>
  H71  VSS(1108)  GROUND  = GND
  H73  DDR1_DQS_DN(3)  BI  = M_B_DQS_DN<3>
  H75  VSS(1107)  GROUND  = GND
  H77  DDR1_DQ(19)  BI  = M_B_DQ<19>
  H79  DDR1_DQS_DP(2)  BI  = M_B_DQS_DP<2>
  H81  DDR1_DQ(21)  BI  = M_B_DQ<21>
  H83  RSVD(271)  BI  = TP_CPU0_RSVD_271
  H85  RSVD(270)  BI  = TP_CPU0_RSVD_270
  J2  VCCIO(69)  POWER  = PVCCIO_CPU0
  J4  VSS(1105)  GROUND  = GND
  J6  UPI1_TX_DN(3)  OUT  = UPI_CPU0_CPU1_P1P1_DN<16>
  J8  UPI1_TX_DP(6)  OUT  = UPI_CPU0_CPU1_P1P1_DP<13>
  J10  VCCIO(58)  POWER  = PVCCIO_CPU0
  J12  VSS(1104)  GROUND  = GND
  J14  VSS(1103)  GROUND  = GND
  J16  VSS(46)  GROUND  = GND
  J18  UPI1_TX_DP(16)  OUT  = UPI_CPU0_CPU1_P1P1_DP<3>
  J20  UPI1_TX_DN(17)  OUT  = UPI_CPU0_CPU1_P1P1_DN<2>
  J22  VSS(1102)  GROUND  = GND
  J24  DDR0_DQS_DN(16)  BI  = M_A_DQS_DN<16>
  J26  VSS(1101)  GROUND  = GND
  J28  VSS(1100)  GROUND  = GND
  J30  DDR0_DQS_DN(15)  BI  = M_A_DQS_DN<15>
  J32  VSS(1099)  GROUND  = GND
  J34  VSS(1098)  GROUND  = GND
  J36  DDR0_DQS_DN(14)  BI  = M_A_DQS_DN<14>
  J38  VSS(1097)  GROUND  = GND
  J40  VSS(1096)  GROUND  = GND
  J42  DDR1_DQS_DN(13)  BI  = M_B_DQS_DN<13>
  J46  RSVD(269)  BI  = TP_CPU0_RSVD_269
  J48  DDR0_MA(13)  OUT  = M_A_MA<13>
  J50  DDR1_CS_N(4)  OUT  = M_B_CS_N<4>
  J52  DDR1_MA(0)  OUT  = M_B_MA<0>
  J54  DDR0_MA(10)  OUT  = M_A_MA<10>
  J56  DDR0_CLK_DN(2)  OUT  = M_A_CLK_DN<2>
  J58  DDR1_MA(1)  OUT  = M_B_MA<1>
  J60  DDR0_ACT_N  OUT  = M_A_ACT_N
  J62  RSVD(268)  BI  = TP_CPU0_RSVD_268
  J64  DDR0_MA(12)  OUT  = M_A_MA<12>
  J66  DDR1_ECC(2)  BI  = M_B_ECC<2>
  J68  DDR1_DQS_DP(17)  BI  = M_B_DQS_DP<17>
  J70  DDR1_ECC(0)  BI  = M_B_ECC<0>
  J72  VSS(1095)  GROUND  = GND
  J74  VSS(1094)  GROUND  = GND
  J76  VSS(1093)  GROUND  = GND
  J78  DDR1_DQ(23)  BI  = M_B_DQ<23>
  J80  DDR1_DQ(17)  BI  = M_B_DQ<17>
  J82  VSS(1092)  GROUND  = GND
  J84  VSS(1091)  GROUND  = GND
  J86  VSS(1243)  GROUND  = GND
  K1  VSS(1090)  GROUND  = GND
  K3  UPI1_TX_DP(1)  OUT  = UPI_CPU0_CPU1_P1P1_DP<18>
  K5  UPI1_TX_DN(2)  OUT  = UPI_CPU0_CPU1_P1P1_DN<17>
  K7  UPI1_TX_DP(5)  OUT  = UPI_CPU0_CPU1_P1P1_DP<14>
  K9  UPI1_TX_DN(6)  OUT  = UPI_CPU0_CPU1_P1P1_DN<13>
  K11  VSS(1089)  GROUND  = GND
  K13  VSS(1088)  GROUND  = GND
  K15  VCCIO(70)  POWER  = PVCCIO_CPU0
  K17  VSS(1087)  GROUND  = GND
  K19  UPI1_TX_DN(15)  OUT  = UPI_CPU0_CPU1_P1P1_DN<4>
  K21  UPI1_TX_DP(19)  OUT  = UPI_CPU0_CPU1_P1P1_DP<0>
  K23  DDR0_DQ(63)  BI  = M_A_DQ<63>
  K25  DDR0_DQ(56)  BI  = M_A_DQ<56>
  K27  VSS(1085)  GROUND  = GND
  K29  DDR0_DQ(54)  BI  = M_A_DQ<54>
  K31  DDR0_DQ(48)  BI  = M_A_DQ<48>
  K33  VSS(1084)  GROUND  = GND
  K35  DDR0_DQ(46)  BI  = M_A_DQ<46>
  K37  DDR0_DQ(40)  BI  = M_A_DQ<40>
  K39  VSS(1083)  GROUND  = GND
  K41  DDR1_DQ(38)  BI  = M_B_DQ<38>
  K43  DDR1_DQ(32)  BI  = M_B_DQ<32>
  K45  DDR0_CS_N(7)  OUT  = M_A_CS_N<7>
  K47  DDR0_MA(17)  OUT  = M_A_MA<17>
  K49  DDR0_MA(15)  OUT  = M_A_MA<15>
  K51  DDR1_CS_N(0)  OUT  = M_B_CS_N<0>
  K53  DDR1_PAR  OUT  = M_B_PAR
  K55  DDR1_BA(1)  OUT  = M_B_BA<1>
  K57  DDR1_MA(2)  OUT  = M_B_MA<2>
  K59  DDR1_MA(9)  OUT  = M_B_MA<9>
  K61  RSVD(267)  BI  = TP_CPU0_RSVD_267
  K63  DDR1_CKE(2)  OUT  = M_B_CKE<2>
  K65  VSS(1082)  GROUND  = GND
  K67  VSS(1081)  GROUND  = GND
  K69  VSS(1080)  GROUND  = GND
  K71  VSS(1079)  GROUND  = GND
  K73  VSS(1078)  GROUND  = GND
  K75  DDR0_DQS_DN(12)  BI  = M_A_DQS_DN<12>
  K77  VSS(1077)  GROUND  = GND
  K79  DDR1_DQS_DN(2)  BI  = M_B_DQS_DN<2>
  K81  VSS(1076)  GROUND  = GND
  K83  VSS(1075)  GROUND  = GND
  K85  VSS(1074)  GROUND  = GND
  L2  VSS(1072)  GROUND  = GND
  L4  UPI1_TX_DN(1)  OUT  = UPI_CPU0_CPU1_P1P1_DN<18>
  L6  VSS(1071)  GROUND  = GND
  L8  VSS(1226)  GROUND  = GND
  L10  VSS(1073)  GROUND  = GND
  L12  UPI1_RX_DN(7)  IN  = UPI_CPU1_CPU0_P1P1_DN<12>
  L14  VCCIO(57)  POWER  = PVCCIO_CPU0
  L16  VCCIO(56)  POWER  = PVCCIO_CPU0
  L18  UPI1_TX_DP(15)  OUT  = UPI_CPU0_CPU1_P1P1_DP<4>
  L20  VSS(1070)  GROUND  = GND
  L22  VSS(1069)  GROUND  = GND
  L24  DDR0_DQS_DP(16)  BI  = M_A_DQS_DP<16>
  L26  DDR0_DQ(60)  BI  = M_A_DQ<60>
  L28  DDR0_DQ(50)  BI  = M_A_DQ<50>
  L30  DDR0_DQS_DP(15)  BI  = M_A_DQS_DP<15>
  L32  DDR0_DQ(52)  BI  = M_A_DQ<52>
  L34  DDR0_DQ(42)  BI  = M_A_DQ<42>
  L36  DDR0_DQS_DP(14)  BI  = M_A_DQS_DP<14>
  L38  DDR0_DQ(44)  BI  = M_A_DQ<44>
  L40  DDR1_DQ(34)  BI  = M_B_DQ<34>
  L42  DDR1_DQS_DP(13)  BI  = M_B_DQS_DP<13>
  L46  VCCD012(13)  POWER  = PVDDQ_ABC
  L48  VCCD012(14)  POWER  = PVDDQ_ABC
  L50  VCCD012(15)  POWER  = PVDDQ_ABC
  L52  VCCD012(16)  POWER  = PVDDQ_ABC
  L54  VCCD012(17)  POWER  = PVDDQ_ABC
  L56  VCCD012(18)  POWER  = PVDDQ_ABC
  L58  VCCD012(19)  POWER  = PVDDQ_ABC
  L60  VCCD012(20)  POWER  = PVDDQ_ABC
  L62  VCCD012(21)  POWER  = PVDDQ_ABC
  L64  DDR1_CKE(3)  OUT  = M_B_CKE<3>
  L66  DDR1_ECC(3)  BI  = M_B_ECC<3>
  L68  DDR1_DQS_DP(8)  BI  = M_B_DQS_DP<8>
  L70  DDR1_ECC(4)  BI  = M_B_ECC<4>
  L72  VSS(1068)  GROUND  = GND
  L74  DDR0_DQ(30)  BI  = M_A_DQ<30>
  L76  DDR0_DQ(24)  BI  = M_A_DQ<24>
  L78  VSS(1067)  GROUND  = GND
  L80  VSS(1066)  GROUND  = GND
  L82  VSS(1065)  GROUND  = GND
  L84  DDR0_DQ(11)  BI  = M_A_DQ<11>
  L86  DDR0_DQ(10)  BI  = M_A_DQ<10>
  M1  UPI0_TX_DP(0)  OUT  = UPI_CPU0_CPU1_P0P0_DP<19>
  M3  UPI1_TX_DN(0)  OUT  = UPI_CPU0_CPU1_P1P1_DN<19>
  M5  UPI1_TX_DP(2)  OUT  = UPI_CPU0_CPU1_P1P1_DP<17>
  M7  VCCIO(71)  POWER  = PVCCIO_CPU0
  M9  VCCIO(72)  POWER  = PVCCIO_CPU0
  M11  VCCIO(53)  POWER  = PVCCIO_CPU0
  M13  UPI1_RX_DP(8)  IN  = UPI_CPU1_CPU0_P1P1_DP<11>
  M15  VSS(1062)  GROUND  = GND
  M17  VSS(1061)  GROUND  = GND
  M19  VSS(1060)  GROUND  = GND
  M21  VCCIO(52)  POWER  = PVCCIO_CPU0
  M23  VSS(1059)  GROUND  = GND
  M25  VSS(1058)  GROUND  = GND
  M27  VSS(1057)  GROUND  = GND
  M29  VSS(1056)  GROUND  = GND
  M31  VSS(1055)  GROUND  = GND
  M33  VSS(1054)  GROUND  = GND
  M35  VSS(1053)  GROUND  = GND
  M37  VSS(1052)  GROUND  = GND
  M39  VSS(1051)  GROUND  = GND
  M41  VSS(1050)  GROUND  = GND
  M43  VSS(1049)  GROUND  = GND
  M45  DDR1_CS_N(6)  OUT  = M_B_CS_N<6>
  M47  DDR1_CID(2)  OUT  = M_B_C<2>
  M49  DDR1_ODT(2)  OUT  = M_B_ODT<2>
  M51  DDR1_MA(13)  OUT  = M_B_MA<13>
  M53  DDR1_CLK_DN(0)  OUT  = M_B_CLK_DN<0>
  M55  DDR1_MA(10)  OUT  = M_B_MA<10>
  M57  DDR1_CLK_DP(2)  OUT  = M_B_CLK_DP<2>
  M59  DDR1_MA(4)  OUT  = M_B_MA<4>
  M61  DDR1_BG(0)  OUT  = M_B_BG<0>
  M63  RSVD(266)  BI  = TP_CPU0_RSVD_266
  M65  VSS(1048)  GROUND  = GND
  M67  DDR1_ECC(7)  BI  = M_B_ECC<7>
  M69  DDR1_ECC(5)  BI  = M_B_ECC<5>
  M71  VSS(1047)  GROUND  = GND
  M73  DDR0_DQ(26)  BI  = M_A_DQ<26>
  M75  DDR0_DQS_DP(12)  BI  = M_A_DQS_DP<12>
  M77  DDR0_DQ(28)  BI  = M_A_DQ<28>
  M79  VSS(1046)  GROUND  = GND
  M81  DDR0_DQ(19)  BI  = M_A_DQ<19>
  M83  VSS(1045)  GROUND  = GND
  M85  VSS(1044)  GROUND  = GND
  N2  UPI0_TX_DN(0)  OUT  = UPI_CPU0_CPU1_P0P0_DN<19>
  N4  VSS(1033)  GROUND  = GND
  N6  VSS(1040)  GROUND  = GND
  N8  VSS(1032)  GROUND  = GND
  N10  UPI1_RX_DP(4)  IN  = UPI_CPU1_CPU0_P1P1_DP<15>
  N12  UPI1_RX_DP(7)  IN  = UPI_CPU1_CPU0_P1P1_DP<12>
  N14  UPI1_RX_DN(8)  IN  = UPI_CPU1_CPU0_P1P1_DN<11>
  N16  UPI1_RX_DP(11)  IN  = UPI_CPU1_CPU0_P1P1_DP<8>
  N18  VCCIO(73)  POWER  = PVCCIO_CPU0
  N20  VSS(1042)  GROUND  = GND
  N22  VSS(1041)  GROUND  = GND
  N24  DDR0_DQS_DN(7)  BI  = M_A_DQS_DN<7>
  N26  DDR0_DQ(61)  BI  = M_A_DQ<61>
  N28  DDR0_DQ(51)  BI  = M_A_DQ<51>
  N30  DDR0_DQS_DP(6)  BI  = M_A_DQS_DP<6>
  N32  DDR0_DQ(53)  BI  = M_A_DQ<53>
  N34  DDR0_DQ(43)  BI  = M_A_DQ<43>
  N36  DDR0_DQS_DP(5)  BI  = M_A_DQS_DP<5>
  N38  DDR0_DQ(45)  BI  = M_A_DQ<45>
  N40  DDR1_DQ(35)  BI  = M_B_DQ<35>
  N42  DDR1_DQS_DN(4)  BI  = M_B_DQS_DN<4>
  N46  DDR1_CS_N(2)  OUT  = M_B_CS_N<2>
  N48  DDR1_MA(17)  OUT  = M_B_MA<17>
  N50  DDR1_ODT(0)  OUT  = M_B_ODT<0>
  N52  DDR1_MA(15)  OUT  = M_B_MA<15>
  N54  DDR1_CLK_DP(0)  OUT  = M_B_CLK_DP<0>
  N56  DDR1_CLK_DN(2)  OUT  = M_B_CLK_DN<2>
  N58  DDR1_MA(3)  OUT  = M_B_MA<3>
  N60  DDR1_BG(1)  OUT  = M_B_BG<1>
  N62  DDR1_CKE(0)  OUT  = M_B_CKE<0>
  N64  VCCD012(22)  POWER  = PVDDQ_ABC
  N66  VSS(1039)  GROUND  = GND
  N68  DDR1_DQS_DN(8)  BI  = M_B_DQS_DN<8>
  N70  VSS(1038)  GROUND  = GND
  N72  VSS(1037)  GROUND  = GND
  N74  VSS(1036)  GROUND  = GND
  N76  VSS(1035)  GROUND  = GND
  N78  VSS(1034)  GROUND  = GND
  N80  DDR0_DQ(23)  BI  = M_A_DQ<23>
  N82  DDR0_DQ(18)  BI  = M_A_DQ<18>
  N84  DDR0_DQ(15)  BI  = M_A_DQ<15>
  N86  DDR0_DQ(14)  BI  = M_A_DQ<14>
  P1  UPI0_TX_DN(1)  OUT  = UPI_CPU0_CPU1_P0P0_DN<18>
  P3  UPI1_TX_DP(0)  OUT  = UPI_CPU0_CPU1_P1P1_DP<19>
  P5  VCCIO(51)  POWER  = PVCCIO_CPU0
  P7  UPI1_RX_DN(1)  IN  = UPI_CPU1_CPU0_P1P1_DN<18>
  P9  UPI1_RX_DN(4)  IN  = UPI_CPU1_CPU0_P1P1_DN<15>
  P11  VSS(1031)  GROUND  = GND
  P13  UPI1_RX_DP(9)  IN  = UPI_CPU1_CPU0_P1P1_DP<10>
  P15  VSS(1030)  GROUND  = GND
  P17  UPI1_RX_DN(11)  IN  = UPI_CPU1_CPU0_P1P1_DN<8>
  P19  UPI1_RX_DP(14)  IN  = UPI_CPU1_CPU0_P1P1_DP<5>
  P21  UPI1_RX_DN(16)  IN  = UPI_CPU1_CPU0_P1P1_DN<3>
  P23  DDR0_DQ(58)  BI  = M_A_DQ<58>
  P25  DDR0_DQ(57)  BI  = M_A_DQ<57>
  P27  VSS(1029)  GROUND  = GND
  P29  DDR0_DQ(55)  BI  = M_A_DQ<55>
  P31  DDR0_DQ(49)  BI  = M_A_DQ<49>
  P33  VSS(1028)  GROUND  = GND
  P35  DDR0_DQ(47)  BI  = M_A_DQ<47>
  P37  DDR0_DQ(41)  BI  = M_A_DQ<41>
  P39  VSS(1027)  GROUND  = GND
  P41  DDR1_DQ(39)  BI  = M_B_DQ<39>
  P43  DDR1_DQ(36)  BI  = M_B_DQ<36>
  P45  VSS(429)  GROUND  = GND
  P47  VSS(453)  GROUND  = GND
  P49  VSS(454)  GROUND  = GND
  P51  VSS(476)  GROUND  = GND
  P53  VSS(483)  GROUND  = GND
  P55  VSS(545)  GROUND  = GND
  P57  VSS(567)  GROUND  = GND
  P59  VSS(578)  GROUND  = GND
  P61  VSS(594)  GROUND  = GND
  P63  VSS(732)  GROUND  = GND
  P65  RSVD(265)  BI  = TP_CPU0_RSVD_265
  P67  VSS(1026)  GROUND  = GND
  P69  VSS(1025)  GROUND  = GND
  P71  VSS(1024)  GROUND  = GND
  P73  DDR0_DQ(27)  BI  = M_A_DQ<27>
  P75  DDR0_DQS_DP(3)  BI  = M_A_DQS_DP<3>
  P77  DDR0_DQ(29)  BI  = M_A_DQ<29>
  P79  DDR0_DQS_DN(2)  BI  = M_A_DQS_DN<2>
  P81  VSS(1023)  GROUND  = GND
